(kicad_pcb
	(version 20260206)
	(generator "pcbnew")
	(generator_version "10.0")
	(general
		(thickness 1.6)
		(legacy_teardrops no)
	)
	(paper "A4")
	(title_block
		(title "04192023_DAF0TMB3IC0_F0TG_MB_C_brd_V02_OCP.brd")
		(comment 1 "Grand Teton / footprints 5284-5290 of 8354")
	)
	(layers
		(0 "F.Cu" signal "TOP")
		(4 "In1.Cu" signal "GND")
		(6 "In2.Cu" signal "IN1")
		(8 "In3.Cu" signal "GND1")
		(10 "In4.Cu" signal "IN2")
		(12 "In5.Cu" signal "GND2")
		(14 "In6.Cu" signal "IN3")
		(16 "In7.Cu" signal "GND3")
		(18 "In8.Cu" signal "VCC")
		(20 "In9.Cu" signal "VCC1")
		(22 "In10.Cu" signal "GND4")
		(24 "In11.Cu" signal "IN4")
		(26 "In12.Cu" signal "GND5")
		(28 "In13.Cu" signal "IN5")
		(30 "In14.Cu" signal "GND6")
		(32 "In15.Cu" signal "IN6")
		(34 "In16.Cu" signal "GND7")
		(2 "B.Cu" signal "BOTTOM")
		(9 "F.Adhes" user "F.Adhesive")
		(11 "B.Adhes" user "B.Adhesive")
		(13 "F.Paste" user "Package Geometry/Pastemask Top")
		(15 "B.Paste" user "Package Geometry/Pastemask Bottom")
		(5 "F.SilkS" user "Ref Des/Silkscreen Top")
		(7 "B.SilkS" user "Ref Des/Silkscreen Bottom")
		(1 "F.Mask" user "Board Geometry/Soldermask Top")
		(3 "B.Mask" user "Board Geometry/Soldermask Bottom")
		(17 "Dwgs.User" user "User.Drawings")
		(19 "Cmts.User" user "User.Comments")
		(21 "Eco1.User" user "User.Eco1")
		(23 "Eco2.User" user "User.Eco2")
		(25 "Edge.Cuts" user "Board Geometry/Outline")
		(27 "Margin" user)
		(31 "F.CrtYd" user "Package Geometry/Place Bound Top")
		(29 "B.CrtYd" user "Package Geometry/Place Bound Bottom")
		(35 "F.Fab" user "Ref Des/Assembly Top")
		(33 "B.Fab" user "Ref Des/Assembly Bottom")
	)
	(footprint ""
		(layer "B.Cu")
		(at 117.895624 -256.505456)
		(property "Reference" "C2430"
			(at 0 0 0)
			(layer "B.SilkS")
			(hide yes)
			(effects
				(font
					(size 1.27 1.27)
				)
				(justify mirror)
			)
		)
		(property "Value" ""
			(at 0 0 0)
			(layer "B.Fab")
			(effects
				(font
					(size 1.27 1.27)
				)
				(justify mirror)
			)
		)
		(duplicate_pad_numbers_are_jumpers no)
		(fp_line
			(start -0.7874 -0.4064)
			(end -0.7874 0.4064)
			(stroke
				(width 0.1524)
				(type default)
			)
			(layer "B.SilkS")
		)
		(fp_line
			(start -0.7874 0.4064)
			(end 0.7874 0.4064)
			(stroke
				(width 0.1524)
				(type default)
			)
			(layer "B.SilkS")
		)
		(fp_line
			(start 0.7874 -0.4064)
			(end -0.7874 -0.4064)
			(stroke
				(width 0.1524)
				(type default)
			)
			(layer "B.SilkS")
		)
		(fp_line
			(start 0.7874 0.4064)
			(end 0.7874 -0.4064)
			(stroke
				(width 0.1524)
				(type default)
			)
			(layer "B.SilkS")
		)
		(fp_line
			(start -0.67945 -0.3048)
			(end -0.67945 0.3048)
			(stroke
				(width 0.1)
				(type default)
			)
			(layer "B.Fab")
		)
		(fp_line
			(start -0.67945 0.3048)
			(end -0.120396 0.3048)
			(stroke
				(width 0.1)
				(type default)
			)
			(layer "B.Fab")
		)
		(fp_line
			(start -0.12065 -0.3048)
			(end -0.67945 -0.3048)
			(stroke
				(width 0.1)
				(type default)
			)
			(layer "B.Fab")
		)
		(fp_line
			(start -0.12065 -0.2794)
			(end -0.12065 -0.3048)
			(stroke
				(width 0.1)
				(type default)
			)
			(layer "B.Fab")
		)
		(fp_line
			(start -0.120396 0.2794)
			(end 0.12065 0.2794)
			(stroke
				(width 0.1)
				(type default)
			)
			(layer "B.Fab")
		)
		(fp_line
			(start -0.120396 0.3048)
			(end -0.120396 0.2794)
			(stroke
				(width 0.1)
				(type default)
			)
			(layer "B.Fab")
		)
		(fp_line
			(start 0.12065 -0.305054)
			(end 0.12065 -0.2794)
			(stroke
				(width 0.1)
				(type default)
			)
			(layer "B.Fab")
		)
		(fp_line
			(start 0.12065 -0.2794)
			(end -0.12065 -0.2794)
			(stroke
				(width 0.1)
				(type default)
			)
			(layer "B.Fab")
		)
		(fp_line
			(start 0.12065 0.2794)
			(end 0.12065 0.3048)
			(stroke
				(width 0.1)
				(type default)
			)
			(layer "B.Fab")
		)
		(fp_line
			(start 0.12065 0.3048)
			(end 0.67945 0.3048)
			(stroke
				(width 0.1)
				(type default)
			)
			(layer "B.Fab")
		)
		(fp_line
			(start 0.67945 -0.305054)
			(end 0.12065 -0.305054)
			(stroke
				(width 0.1)
				(type default)
			)
			(layer "B.Fab")
		)
		(fp_line
			(start 0.67945 0.3048)
			(end 0.67945 -0.305054)
			(stroke
				(width 0.1)
				(type default)
			)
			(layer "B.Fab")
		)
		(pad "1" smd circle
			(at 0.40005 0 180)
			(size 0 0)
			(layers "B.Cu" "B.Mask" "B.Paste")
			(net "PVDDCR_SOC_P1")
		)
		(pad "2" smd circle
			(at -0.40005 0 180)
			(size 0 0)
			(layers "B.Cu" "B.Mask" "B.Paste")
			(net "GND")
		)
	)
	(footprint ""
		(layer "B.Cu")
		(at 367.671858 -136.986772)
		(property "Reference" "C461"
			(at 0 0 0)
			(layer "B.SilkS")
			(hide yes)
			(effects
				(font
					(size 1.27 1.27)
				)
				(justify mirror)
			)
		)
		(property "Value" ""
			(at 0 0 0)
			(layer "B.Fab")
			(effects
				(font
					(size 1.27 1.27)
				)
				(justify mirror)
			)
		)
		(duplicate_pad_numbers_are_jumpers no)
		(fp_line
			(start -0.7874 -0.4064)
			(end -0.7874 0.4064)
			(stroke
				(width 0.1524)
				(type default)
			)
			(layer "B.SilkS")
		)
		(fp_line
			(start -0.7874 0.4064)
			(end 0.7874 0.4064)
			(stroke
				(width 0.1524)
				(type default)
			)
			(layer "B.SilkS")
		)
		(fp_line
			(start 0.7874 -0.4064)
			(end -0.7874 -0.4064)
			(stroke
				(width 0.1524)
				(type default)
			)
			(layer "B.SilkS")
		)
		(fp_line
			(start 0.7874 0.4064)
			(end 0.7874 -0.4064)
			(stroke
				(width 0.1524)
				(type default)
			)
			(layer "B.SilkS")
		)
		(fp_line
			(start -0.67945 -0.3048)
			(end -0.67945 0.3048)
			(stroke
				(width 0.1)
				(type default)
			)
			(layer "B.Fab")
		)
		(fp_line
			(start -0.67945 0.3048)
			(end -0.120396 0.3048)
			(stroke
				(width 0.1)
				(type default)
			)
			(layer "B.Fab")
		)
		(fp_line
			(start -0.12065 -0.3048)
			(end -0.67945 -0.3048)
			(stroke
				(width 0.1)
				(type default)
			)
			(layer "B.Fab")
		)
		(fp_line
			(start -0.12065 -0.2794)
			(end -0.12065 -0.3048)
			(stroke
				(width 0.1)
				(type default)
			)
			(layer "B.Fab")
		)
		(fp_line
			(start -0.120396 0.2794)
			(end 0.12065 0.2794)
			(stroke
				(width 0.1)
				(type default)
			)
			(layer "B.Fab")
		)
		(fp_line
			(start -0.120396 0.3048)
			(end -0.120396 0.2794)
			(stroke
				(width 0.1)
				(type default)
			)
			(layer "B.Fab")
		)
		(fp_line
			(start 0.12065 -0.305054)
			(end 0.12065 -0.2794)
			(stroke
				(width 0.1)
				(type default)
			)
			(layer "B.Fab")
		)
		(fp_line
			(start 0.12065 -0.2794)
			(end -0.12065 -0.2794)
			(stroke
				(width 0.1)
				(type default)
			)
			(layer "B.Fab")
		)
		(fp_line
			(start 0.12065 0.2794)
			(end 0.12065 0.3048)
			(stroke
				(width 0.1)
				(type default)
			)
			(layer "B.Fab")
		)
		(fp_line
			(start 0.12065 0.3048)
			(end 0.67945 0.3048)
			(stroke
				(width 0.1)
				(type default)
			)
			(layer "B.Fab")
		)
		(fp_line
			(start 0.67945 -0.305054)
			(end 0.12065 -0.305054)
			(stroke
				(width 0.1)
				(type default)
			)
			(layer "B.Fab")
		)
		(fp_line
			(start 0.67945 0.3048)
			(end 0.67945 -0.305054)
			(stroke
				(width 0.1)
				(type default)
			)
			(layer "B.Fab")
		)
		(pad "1" smd circle
			(at 0.40005 0 180)
			(size 0 0)
			(layers "B.Cu" "B.Mask" "B.Paste")
			(net "PVDDCR_SOC_P0_EN_RC")
		)
		(pad "2" smd circle
			(at -0.40005 0 180)
			(size 0 0)
			(layers "B.Cu" "B.Mask" "B.Paste")
			(net "GND")
		)
	)
	(footprint ""
		(layer "B.Cu")
		(at 119.674386 -264.354564)
		(property "Reference" "C2119"
			(at 0 0 0)
			(layer "B.SilkS")
			(hide yes)
			(effects
				(font
					(size 1.27 1.27)
				)
				(justify mirror)
			)
		)
		(property "Value" ""
			(at 0 0 0)
			(layer "B.Fab")
			(effects
				(font
					(size 1.27 1.27)
				)
				(justify mirror)
			)
		)
		(duplicate_pad_numbers_are_jumpers no)
		(fp_line
			(start -0.7874 -0.4064)
			(end -0.7874 0.4064)
			(stroke
				(width 0.1524)
				(type default)
			)
			(layer "B.SilkS")
		)
		(fp_line
			(start -0.7874 0.4064)
			(end 0.7874 0.4064)
			(stroke
				(width 0.1524)
				(type default)
			)
			(layer "B.SilkS")
		)
		(fp_line
			(start 0.7874 -0.4064)
			(end -0.7874 -0.4064)
			(stroke
				(width 0.1524)
				(type default)
			)
			(layer "B.SilkS")
		)
		(fp_line
			(start 0.7874 0.4064)
			(end 0.7874 -0.4064)
			(stroke
				(width 0.1524)
				(type default)
			)
			(layer "B.SilkS")
		)
		(fp_line
			(start -0.67945 -0.3048)
			(end -0.67945 0.3048)
			(stroke
				(width 0.1)
				(type default)
			)
			(layer "B.Fab")
		)
		(fp_line
			(start -0.67945 0.3048)
			(end -0.120396 0.3048)
			(stroke
				(width 0.1)
				(type default)
			)
			(layer "B.Fab")
		)
		(fp_line
			(start -0.12065 -0.3048)
			(end -0.67945 -0.3048)
			(stroke
				(width 0.1)
				(type default)
			)
			(layer "B.Fab")
		)
		(fp_line
			(start -0.12065 -0.2794)
			(end -0.12065 -0.3048)
			(stroke
				(width 0.1)
				(type default)
			)
			(layer "B.Fab")
		)
		(fp_line
			(start -0.120396 0.2794)
			(end 0.12065 0.2794)
			(stroke
				(width 0.1)
				(type default)
			)
			(layer "B.Fab")
		)
		(fp_line
			(start -0.120396 0.3048)
			(end -0.120396 0.2794)
			(stroke
				(width 0.1)
				(type default)
			)
			(layer "B.Fab")
		)
		(fp_line
			(start 0.12065 -0.305054)
			(end 0.12065 -0.2794)
			(stroke
				(width 0.1)
				(type default)
			)
			(layer "B.Fab")
		)
		(fp_line
			(start 0.12065 -0.2794)
			(end -0.12065 -0.2794)
			(stroke
				(width 0.1)
				(type default)
			)
			(layer "B.Fab")
		)
		(fp_line
			(start 0.12065 0.2794)
			(end 0.12065 0.3048)
			(stroke
				(width 0.1)
				(type default)
			)
			(layer "B.Fab")
		)
		(fp_line
			(start 0.12065 0.3048)
			(end 0.67945 0.3048)
			(stroke
				(width 0.1)
				(type default)
			)
			(layer "B.Fab")
		)
		(fp_line
			(start 0.67945 -0.305054)
			(end 0.12065 -0.305054)
			(stroke
				(width 0.1)
				(type default)
			)
			(layer "B.Fab")
		)
		(fp_line
			(start 0.67945 0.3048)
			(end 0.67945 -0.305054)
			(stroke
				(width 0.1)
				(type default)
			)
			(layer "B.Fab")
		)
		(pad "1" smd circle
			(at 0.40005 0 180)
			(size 0 0)
			(layers "B.Cu" "B.Mask" "B.Paste")
			(net "PVDD11_S3_P1")
		)
		(pad "2" smd circle
			(at -0.40005 0 180)
			(size 0 0)
			(layers "B.Cu" "B.Mask" "B.Paste")
			(net "GND")
		)
	)
	(footprint ""
		(layer "B.Cu")
		(at 139.562586 -389.673084 90)
		(property "Reference" "C404"
			(at 0 0 90)
			(layer "B.SilkS")
			(hide yes)
			(effects
				(font
					(size 1.27 1.27)
				)
				(justify mirror)
			)
		)
		(property "Value" ""
			(at 0 0 90)
			(layer "B.Fab")
			(effects
				(font
					(size 1.27 1.27)
				)
				(justify mirror)
			)
		)
		(duplicate_pad_numbers_are_jumpers no)
		(fp_line
			(start 1.524 -0.762)
			(end -1.524 -0.762)
			(stroke
				(width 0.1524)
				(type default)
			)
			(layer "B.SilkS")
		)
		(fp_line
			(start -1.524 -0.762)
			(end -1.524 0.762)
			(stroke
				(width 0.1524)
				(type default)
			)
			(layer "B.SilkS")
		)
		(fp_line
			(start 1.524 0.762)
			(end 1.524 -0.762)
			(stroke
				(width 0.1524)
				(type default)
			)
			(layer "B.SilkS")
		)
		(fp_line
			(start -1.524 0.762)
			(end 1.524 0.762)
			(stroke
				(width 0.1524)
				(type default)
			)
			(layer "B.SilkS")
		)
		(fp_line
			(start 1.1049 -0.724916)
			(end 1.1049 0.724916)
			(stroke
				(width 0.1)
				(type default)
			)
			(layer "B.Fab")
		)
		(fp_line
			(start -1.1049 -0.724916)
			(end 1.1049 -0.724916)
			(stroke
				(width 0.1)
				(type default)
			)
			(layer "B.Fab")
		)
		(fp_line
			(start 1.1049 0.724916)
			(end -1.1049 0.724916)
			(stroke
				(width 0.1)
				(type default)
			)
			(layer "B.Fab")
		)
		(fp_line
			(start -1.1049 0.724916)
			(end -1.1049 -0.724916)
			(stroke
				(width 0.1)
				(type default)
			)
			(layer "B.Fab")
		)
		(pad "1" smd rect
			(at 0.889 0 90)
			(size 1.016 1.27)
			(layers "B.Cu" "B.Mask" "B.Paste")
			(net "P0V9_CPU1_RT_2D")
		)
		(pad "2" smd rect
			(at -0.889 0 90)
			(size 1.016 1.27)
			(layers "B.Cu" "B.Mask" "B.Paste")
			(net "GND")
		)
	)
	(footprint ""
		(layer "B.Cu")
		(at 370.618512 -396.393162 -90)
		(property "Reference" "C1052"
			(at 0 0 90)
			(layer "B.SilkS")
			(hide yes)
			(effects
				(font
					(size 1.27 1.27)
				)
				(justify mirror)
			)
		)
		(property "Value" ""
			(at 0 0 90)
			(layer "B.Fab")
			(effects
				(font
					(size 1.27 1.27)
				)
				(justify mirror)
			)
		)
		(duplicate_pad_numbers_are_jumpers no)
		(fp_line
			(start -0.299974 0.150114)
			(end 0.299974 0.150114)
			(stroke
				(width 0.1)
				(type default)
			)
			(layer "B.Fab")
		)
		(fp_line
			(start 0.299974 0.150114)
			(end 0.299974 -0.150114)
			(stroke
				(width 0.1)
				(type default)
			)
			(layer "B.Fab")
		)
		(fp_line
			(start -0.299974 -0.150114)
			(end -0.299974 0.150114)
			(stroke
				(width 0.1)
				(type default)
			)
			(layer "B.Fab")
		)
		(fp_line
			(start 0.299974 -0.150114)
			(end -0.299974 -0.150114)
			(stroke
				(width 0.1)
				(type default)
			)
			(layer "B.Fab")
		)
		(pad "1" smd rect
			(at 0.2667 0 90)
			(size 0.3048 0.381)
			(layers "B.Cu" "B.Mask" "B.Paste")
			(net "P0V9_CPU0_RT3_2A")
		)
		(pad "2" smd rect
			(at -0.2667 0 90)
			(size 0.3048 0.381)
			(layers "B.Cu" "B.Mask" "B.Paste")
			(net "GND")
		)
	)
	(footprint ""
		(layer "B.Cu")
		(at 365.519462 -398.969484)
		(property "Reference" "C1029"
			(at 0 0 0)
			(layer "B.SilkS")
			(hide yes)
			(effects
				(font
					(size 1.27 1.27)
				)
				(justify mirror)
			)
		)
		(property "Value" ""
			(at 0 0 0)
			(layer "B.Fab")
			(effects
				(font
					(size 1.27 1.27)
				)
				(justify mirror)
			)
		)
		(duplicate_pad_numbers_are_jumpers no)
		(fp_line
			(start -1.524 -0.762)
			(end -1.524 0.762)
			(stroke
				(width 0.1524)
				(type default)
			)
			(layer "B.SilkS")
		)
		(fp_line
			(start -1.524 0.762)
			(end 1.524 0.762)
			(stroke
				(width 0.1524)
				(type default)
			)
			(layer "B.SilkS")
		)
		(fp_line
			(start 1.524 -0.762)
			(end -1.524 -0.762)
			(stroke
				(width 0.1524)
				(type default)
			)
			(layer "B.SilkS")
		)
		(fp_line
			(start 1.524 0.762)
			(end 1.524 -0.762)
			(stroke
				(width 0.1524)
				(type default)
			)
			(layer "B.SilkS")
		)
		(fp_line
			(start -1.1049 -0.724916)
			(end 1.1049 -0.724916)
			(stroke
				(width 0.1)
				(type default)
			)
			(layer "B.Fab")
		)
		(fp_line
			(start -1.1049 0.724916)
			(end -1.1049 -0.724916)
			(stroke
				(width 0.1)
				(type default)
			)
			(layer "B.Fab")
		)
		(fp_line
			(start 1.1049 -0.724916)
			(end 1.1049 0.724916)
			(stroke
				(width 0.1)
				(type default)
			)
			(layer "B.Fab")
		)
		(fp_line
			(start 1.1049 0.724916)
			(end -1.1049 0.724916)
			(stroke
				(width 0.1)
				(type default)
			)
			(layer "B.Fab")
		)
		(pad "1" smd rect
			(at 0.889 0)
			(size 1.016 1.27)
			(layers "B.Cu" "B.Mask" "B.Paste")
			(net "P0V9_CPU0_RT3_2A")
		)
		(pad "2" smd rect
			(at -0.889 0)
			(size 1.016 1.27)
			(layers "B.Cu" "B.Mask" "B.Paste")
			(net "GND")
		)
	)
	(footprint ""
		(layer "B.Cu")
		(at 241.427 -234.061 -90)
		(property "Reference" "R145"
			(at 0 0 90)
			(layer "B.SilkS")
			(hide yes)
			(effects
				(font
					(size 1.27 1.27)
				)
				(justify mirror)
			)
		)
		(property "Value" ""
			(at 0 0 90)
			(layer "B.Fab")
			(effects
				(font
					(size 1.27 1.27)
				)
				(justify mirror)
			)
		)
		(duplicate_pad_numbers_are_jumpers no)
		(fp_line
			(start -0.7874 0.4064)
			(end 0.7874 0.4064)
			(stroke
				(width 0.1524)
				(type default)
			)
			(layer "B.SilkS")
		)
		(fp_line
			(start 0.7874 0.4064)
			(end 0.7874 -0.4064)
			(stroke
				(width 0.1524)
				(type default)
			)
			(layer "B.SilkS")
		)
		(fp_line
			(start -0.7874 -0.4064)
			(end -0.7874 0.4064)
			(stroke
				(width 0.1524)
				(type default)
			)
			(layer "B.SilkS")
		)
		(fp_line
			(start 0.7874 -0.4064)
			(end -0.7874 -0.4064)
			(stroke
				(width 0.1524)
				(type default)
			)
			(layer "B.SilkS")
		)
		(fp_line
			(start -0.67945 0.3048)
			(end -0.120396 0.3048)
			(stroke
				(width 0.1)
				(type default)
			)
			(layer "B.Fab")
		)
		(fp_line
			(start -0.120396 0.3048)
			(end -0.120396 0.2794)
			(stroke
				(width 0.1)
				(type default)
			)
			(layer "B.Fab")
		)
		(fp_line
			(start 0.12065 0.3048)
			(end 0.67945 0.3048)
			(stroke
				(width 0.1)
				(type default)
			)
			(layer "B.Fab")
		)
		(fp_line
			(start 0.67945 0.3048)
			(end 0.67945 -0.305054)
			(stroke
				(width 0.1)
				(type default)
			)
			(layer "B.Fab")
		)
		(fp_line
			(start -0.120396 0.2794)
			(end 0.12065 0.2794)
			(stroke
				(width 0.1)
				(type default)
			)
			(layer "B.Fab")
		)
		(fp_line
			(start 0.12065 0.2794)
			(end 0.12065 0.3048)
			(stroke
				(width 0.1)
				(type default)
			)
			(layer "B.Fab")
		)
		(fp_line
			(start -0.12065 -0.2794)
			(end -0.12065 -0.3048)
			(stroke
				(width 0.1)
				(type default)
			)
			(layer "B.Fab")
		)
		(fp_line
			(start 0.12065 -0.2794)
			(end -0.12065 -0.2794)
			(stroke
				(width 0.1)
				(type default)
			)
			(layer "B.Fab")
		)
		(fp_line
			(start -0.67945 -0.3048)
			(end -0.67945 0.3048)
			(stroke
				(width 0.1)
				(type default)
			)
			(layer "B.Fab")
		)
		(fp_line
			(start -0.12065 -0.3048)
			(end -0.67945 -0.3048)
			(stroke
				(width 0.1)
				(type default)
			)
			(layer "B.Fab")
		)
		(fp_line
			(start 0.12065 -0.305054)
			(end 0.12065 -0.2794)
			(stroke
				(width 0.1)
				(type default)
			)
			(layer "B.Fab")
		)
		(fp_line
			(start 0.67945 -0.305054)
			(end 0.12065 -0.305054)
			(stroke
				(width 0.1)
				(type default)
			)
			(layer "B.Fab")
		)
		(pad "1" smd circle
			(at 0.40005 0 90)
			(size 0 0)
			(layers "B.Cu" "B.Mask" "B.Paste")
			(net "SMB_CPU0_CPU1_SEC_SCL_R2")
		)
		(pad "2" smd circle
			(at -0.40005 0 90)
			(size 0 0)
			(layers "B.Cu" "B.Mask" "B.Paste")
			(net "SMB_CPU0_SEC_R_SCL")
		)
	)
)
